(kicad_pcb
	(version 20240108)
	(generator "pcbnew")
	(generator_version "8.0")
	(general
		(thickness 1.62)
		(legacy_teardrops no)
	)
	(paper "A4")
	(title_block
		(title "Jetson Orin Baseboard")
		(date "2025-03-12")
		(rev "1.3.4")
		(company "Antmicro Ltd")
		(comment 1 "www.antmicro.com")
		(comment 9 "footprints 129-131 of 677")
	)
	(layers
		(0 "F.Cu" signal)
		(1 "In1.Cu" signal)
		(2 "In2.Cu" signal)
		(3 "In3.Cu" signal)
		(4 "In4.Cu" jumper)
		(5 "In5.Cu" signal)
		(6 "In6.Cu" signal)
		(31 "B.Cu" signal)
		(32 "B.Adhes" user "B.Adhesive")
		(33 "F.Adhes" user "F.Adhesive")
		(34 "B.Paste" user)
		(35 "F.Paste" user)
		(36 "B.SilkS" user "B.Silkscreen")
		(37 "F.SilkS" user "F.Silkscreen")
		(38 "B.Mask" user)
		(39 "F.Mask" user)
		(40 "Dwgs.User" user "User.Drawings")
		(41 "Cmts.User" user "User.Comments")
		(42 "Eco1.User" user "User.Eco1")
		(43 "Eco2.User" user "User.Eco2")
		(44 "Edge.Cuts" user)
		(45 "Margin" user)
		(46 "B.CrtYd" user "B.Courtyard")
		(47 "F.CrtYd" user "F.Courtyard")
		(48 "B.Fab" user)
		(49 "F.Fab" user)
	)
	(footprint "antmicro-footprints:Spacer_Drill3.7mm_H6.5mm_9774065151R"
		(locked yes)
		(layer "F.Cu")
		(at 60.925 118.1)
		(descr "Spacer M=3 h=6.5mm fi=5.1mm")
		(property "Reference" "H1"
			(at -3.425 -2.6 0)
			(layer "F.SilkS")
			(effects
				(font
					(size 0.7 0.7)
					(thickness 0.15)
				)
				(justify left bottom)
			)
		)
		(property "Value" "Spacer_Drill3.7mm_H6.5mm_9774065151R"
			(at 0 4 0)
			(layer "F.Fab")
			(effects
				(font
					(size 0.7 0.7)
					(thickness 0.15)
				)
				(justify left bottom)
			)
		)
		(property "Footprint" "antmicro-footprints:Spacer_Drill3.7mm_H6.5mm_9774065151R"
			(at 0 0 0)
			(layer "F.Fab")
			(hide yes)
			(effects
				(font
					(size 1.27 1.27)
					(thickness 0.15)
				)
			)
		)
		(property "Datasheet" "https://www.we-online.com/components/products/datasheet/9774065151R.pdf"
			(at 0 0 0)
			(layer "F.Fab")
			(hide yes)
			(effects
				(font
					(size 1.27 1.27)
					(thickness 0.15)
				)
			)
		)
		(property "Author" "Antmicro"
			(at 0 0 0)
			(layer "F.Fab")
			(hide yes)
			(effects
				(font
					(size 1 1)
					(thickness 0.15)
				)
			)
		)
		(property "License" "Apache-2.0"
			(at 0 0 0)
			(layer "F.Fab")
			(hide yes)
			(effects
				(font
					(size 1 1)
					(thickness 0.15)
				)
			)
		)
		(property "MPN" "9774065151R"
			(at 0 0 0)
			(layer "F.Fab")
			(hide yes)
			(effects
				(font
					(size 1 1)
					(thickness 0.15)
				)
			)
		)
		(property "Manufacturer" "Würth Elektronik"
			(at 0 0 0)
			(layer "F.Fab")
			(hide yes)
			(effects
				(font
					(size 1 1)
					(thickness 0.15)
				)
			)
		)
		(sheetname "SoM")
		(sheetfile "som.kicad_sch")
		(solder_paste_ratio -1)
		(attr smd)
		(fp_circle
			(center 0 0)
			(end 3.05 0)
			(stroke
				(width 0.05)
				(type solid)
			)
			(fill none)
			(layer "F.CrtYd")
		)
		(fp_circle
			(center 0 0)
			(end 2.6 0)
			(stroke
				(width 0.15)
				(type solid)
			)
			(fill none)
			(layer "F.Fab")
		)
		(fp_text user "${REFERENCE}"
			(at -3.05041 8.3 0)
			(layer "F.Fab")
			(hide yes)
			(effects
				(font
					(size 0.7 0.7)
					(thickness 0.15)
				)
				(justify left bottom)
			)
		)
		(fp_text user "Author: Antmicro"
			(at -3.05041 7.1 0)
			(layer "F.Fab")
			(hide yes)
			(effects
				(font
					(size 0.7 0.7)
					(thickness 0.15)
				)
				(justify left bottom)
			)
		)
		(fp_text user "License: Apache-2.0"
			(at -3.05041 5.9 0)
			(layer "F.Fab")
			(hide yes)
			(effects
				(font
					(size 0.7 0.7)
					(thickness 0.15)
				)
				(justify left bottom)
			)
		)
		(pad "" smd custom
			(at -1.7 -1.7)
			(size 0.62 0.62)
			(layers "F.Paste")
			(thermal_bridge_angle 90)
			(options
				(clearance outline)
				(anchor circle)
			)
			(primitives
				(gr_arc
					(start -0.250195 1.279127)
					(mid 0.285453 0.294389)
					(end 1.266786 -0.24747)
					(width 0.2)
				)
				(gr_arc
					(start -0.34334 1.279127)
					(mid 0.218448 0.232561)
					(end 1.259603 -0.339191)
					(width 0.2)
				)
				(gr_arc
					(start -0.436309 1.279127)
					(mid 0.152481 0.169693)
					(end 1.255279 -0.431435)
					(width 0.2)
				)
				(gr_arc
					(start -0.529126 1.279127)
					(mid 0.087542 0.105784)
					(end 1.253811 -0.524161)
					(width 0.2)
				)
				(gr_arc
					(start -0.621807 1.279127)
					(mid 0.0309 0.033527)
					(end 1.275473 -0.621136)
					(width 0.2)
				)
				(gr_arc
					(start -0.71437 1.279127)
					(mid -0.037758 -0.026651)
					(end 1.263664 -0.711602)
					(width 0.2)
				)
				(gr_arc
					(start -0.806826 1.279127)
					(mid -0.105837 -0.087395)
					(end 1.253435 -0.802342)
					(width 0.2)
				)
				(gr_arc
					(start -0.899187 1.279127)
					(mid -0.165236 -0.156885)
					(end 1.267475 -0.897258)
					(width 0.2)
				)
				(gr_arc
					(start -0.991463 1.279127)
					(mid -0.228522 -0.222449)
					(end 1.270645 -0.990112)
					(width 0.2)
				)
				(gr_arc
					(start -1.083663 1.279127)
					(mid -0.294507 -0.285313)
					(end 1.266278 -1.081674)
					(width 0.2)
				)
				(gr_line
					(start 1.279127 -0.250195)
					(end 1.279127 -1.083663)
					(width 0.2)
				)
				(gr_line
					(start -0.250195 1.279127)
					(end -1.083663 1.279127)
					(width 0.2)
				)
			)
		)
		(pad "" smd custom
			(at -1.7 1.7 90)
			(size 0.62 0.62)
			(layers "F.Paste")
			(thermal_bridge_angle 90)
			(options
				(clearance outline)
				(anchor circle)
			)
			(primitives
				(gr_arc
					(start -0.250195 1.279127)
					(mid 0.285453 0.294389)
					(end 1.266786 -0.24747)
					(width 0.2)
				)
				(gr_arc
					(start -0.34334 1.279127)
					(mid 0.218448 0.232561)
					(end 1.259603 -0.339191)
					(width 0.2)
				)
				(gr_arc
					(start -0.436309 1.279127)
					(mid 0.152481 0.169693)
					(end 1.255279 -0.431435)
					(width 0.2)
				)
				(gr_arc
					(start -0.529126 1.279127)
					(mid 0.087542 0.105784)
					(end 1.253811 -0.524161)
					(width 0.2)
				)
				(gr_arc
					(start -0.621807 1.279127)
					(mid 0.0309 0.033527)
					(end 1.275473 -0.621136)
					(width 0.2)
				)
				(gr_arc
					(start -0.71437 1.279127)
					(mid -0.037758 -0.026651)
					(end 1.263664 -0.711602)
					(width 0.2)
				)
				(gr_arc
					(start -0.806826 1.279127)
					(mid -0.105837 -0.087395)
					(end 1.253435 -0.802342)
					(width 0.2)
				)
				(gr_arc
					(start -0.899187 1.279127)
					(mid -0.165236 -0.156885)
					(end 1.267475 -0.897258)
					(width 0.2)
				)
				(gr_arc
					(start -0.991463 1.279127)
					(mid -0.228522 -0.222449)
					(end 1.270645 -0.990112)
					(width 0.2)
				)
				(gr_arc
					(start -1.083663 1.279127)
					(mid -0.294507 -0.285313)
					(end 1.266278 -1.081674)
					(width 0.2)
				)
				(gr_line
					(start 1.279127 -0.250195)
					(end 1.279127 -1.083663)
					(width 0.2)
				)
				(gr_line
					(start -0.250195 1.279127)
					(end -1.083663 1.279127)
					(width 0.2)
				)
			)
		)
		(pad "" smd custom
			(at 1.7 -1.7 270)
			(size 0.62 0.62)
			(layers "F.Paste")
			(thermal_bridge_angle 90)
			(options
				(clearance outline)
				(anchor circle)
			)
			(primitives
				(gr_arc
					(start -0.250195 1.279127)
					(mid 0.285453 0.294389)
					(end 1.266786 -0.24747)
					(width 0.2)
				)
				(gr_arc
					(start -0.34334 1.279127)
					(mid 0.218448 0.232561)
					(end 1.259603 -0.339191)
					(width 0.2)
				)
				(gr_arc
					(start -0.436309 1.279127)
					(mid 0.152481 0.169693)
					(end 1.255279 -0.431435)
					(width 0.2)
				)
				(gr_arc
					(start -0.529126 1.279127)
					(mid 0.087542 0.105784)
					(end 1.253811 -0.524161)
					(width 0.2)
				)
				(gr_arc
					(start -0.621807 1.279127)
					(mid 0.0309 0.033527)
					(end 1.275473 -0.621136)
					(width 0.2)
				)
				(gr_arc
					(start -0.71437 1.279127)
					(mid -0.037758 -0.026651)
					(end 1.263664 -0.711602)
					(width 0.2)
				)
				(gr_arc
					(start -0.806826 1.279127)
					(mid -0.105837 -0.087395)
					(end 1.253435 -0.802342)
					(width 0.2)
				)
				(gr_arc
					(start -0.899187 1.279127)
					(mid -0.165236 -0.156885)
					(end 1.267475 -0.897258)
					(width 0.2)
				)
				(gr_arc
					(start -0.991463 1.279127)
					(mid -0.228522 -0.222449)
					(end 1.270645 -0.990112)
					(width 0.2)
				)
				(gr_arc
					(start -1.083663 1.279127)
					(mid -0.294507 -0.285313)
					(end 1.266278 -1.081674)
					(width 0.2)
				)
				(gr_line
					(start 1.279127 -0.250195)
					(end 1.279127 -1.083663)
					(width 0.2)
				)
				(gr_line
					(start -0.250195 1.279127)
					(end -1.083663 1.279127)
					(width 0.2)
				)
			)
		)
		(pad "" smd custom
			(at 1.7 1.7 180)
			(size 0.62 0.62)
			(layers "F.Paste")
			(thermal_bridge_angle 90)
			(options
				(clearance outline)
				(anchor circle)
			)
			(primitives
				(gr_arc
					(start -0.250195 1.279127)
					(mid 0.285453 0.294389)
					(end 1.266786 -0.24747)
					(width 0.2)
				)
				(gr_arc
					(start -0.34334 1.279127)
					(mid 0.218448 0.232561)
					(end 1.259603 -0.339191)
					(width 0.2)
				)
				(gr_arc
					(start -0.436309 1.279127)
					(mid 0.152481 0.169693)
					(end 1.255279 -0.431435)
					(width 0.2)
				)
				(gr_arc
					(start -0.529126 1.279127)
					(mid 0.087542 0.105784)
					(end 1.253811 -0.524161)
					(width 0.2)
				)
				(gr_arc
					(start -0.621807 1.279127)
					(mid 0.0309 0.033527)
					(end 1.275473 -0.621136)
					(width 0.2)
				)
				(gr_arc
					(start -0.71437 1.279127)
					(mid -0.037758 -0.026651)
					(end 1.263664 -0.711602)
					(width 0.2)
				)
				(gr_arc
					(start -0.806826 1.279127)
					(mid -0.105837 -0.087395)
					(end 1.253435 -0.802342)
					(width 0.2)
				)
				(gr_arc
					(start -0.899187 1.279127)
					(mid -0.165236 -0.156885)
					(end 1.267475 -0.897258)
					(width 0.2)
				)
				(gr_arc
					(start -0.991463 1.279127)
					(mid -0.228522 -0.222449)
					(end 1.270645 -0.990112)
					(width 0.2)
				)
				(gr_arc
					(start -1.083663 1.279127)
					(mid -0.294507 -0.285313)
					(end 1.266278 -1.081674)
					(width 0.2)
				)
				(gr_line
					(start 1.279127 -0.250195)
					(end 1.279127 -1.083663)
					(width 0.2)
				)
				(gr_line
					(start -0.250195 1.279127)
					(end -1.083663 1.279127)
					(width 0.2)
				)
			)
		)
		(pad "1" thru_hole circle
			(at 0 0)
			(size 6 6)
			(drill 3.7)
			(layers "*.Cu" "*.Mask")
			(remove_unused_layers no)
			(net 1 "GND")
			(pintype "passive")
		)
	)
	(footprint "antmicro-footprints:R_0402_1005Metric"
		(layer "F.Cu")
		(at 61.6 105)
		(descr "Resistor SMD 0402")
		(tags "resistor SMD 0402")
		(property "Reference" "R76"
			(at 0.75 0.475 0)
			(layer "F.SilkS")
			(effects
				(font
					(size 0.7 0.7)
					(thickness 0.15)
				)
				(justify left bottom)
			)
		)
		(property "Value" "R_0R_0402"
			(at 0 1.4 0)
			(layer "F.Fab")
			(effects
				(font
					(size 0.7 0.7)
					(thickness 0.15)
				)
				(justify left bottom)
			)
		)
		(property "Footprint" "antmicro-footprints:R_0402_1005Metric"
			(at 0 0 0)
			(layer "F.Fab")
			(hide yes)
			(effects
				(font
					(size 1.27 1.27)
					(thickness 0.15)
				)
			)
		)
		(property "Datasheet" "https://industrial.panasonic.com/cdbs/www-data/pdf/RDA0000/AOA0000C301.pdf"
			(at 0 0 0)
			(layer "F.Fab")
			(hide yes)
			(effects
				(font
					(size 1.27 1.27)
					(thickness 0.15)
				)
			)
		)
		(property "Author" "Antmicro"
			(at 0 0 0)
			(layer "F.Fab")
			(hide yes)
			(effects
				(font
					(size 1 1)
					(thickness 0.15)
				)
			)
		)
		(property "Current" "1A"
			(at 0 0 0)
			(layer "F.Fab")
			(hide yes)
			(effects
				(font
					(size 1 1)
					(thickness 0.15)
				)
			)
		)
		(property "License" "Apache-2.0"
			(at 0 0 0)
			(layer "F.Fab")
			(hide yes)
			(effects
				(font
					(size 1 1)
					(thickness 0.15)
				)
			)
		)
		(property "MPN" "ERJ2GE0R00X"
			(at 0 0 0)
			(layer "F.Fab")
			(hide yes)
			(effects
				(font
					(size 1 1)
					(thickness 0.15)
				)
			)
		)
		(property "Manufacturer" "Panasonic"
			(at 0 0 0)
			(layer "F.Fab")
			(hide yes)
			(effects
				(font
					(size 1 1)
					(thickness 0.15)
				)
			)
		)
		(property "Tolerance" ""
			(at 0 0 0)
			(layer "F.Fab")
			(hide yes)
			(effects
				(font
					(size 1 1)
					(thickness 0.15)
				)
			)
		)
		(property "Val" "0R"
			(at 0 0 0)
			(layer "F.Fab")
			(hide yes)
			(effects
				(font
					(size 1 1)
					(thickness 0.15)
				)
			)
		)
		(sheetname "USB Debug, DP")
		(sheetfile "usb.kicad_sch")
		(attr smd)
		(fp_rect
			(start -0.925 -0.47)
			(end 0.925 0.47)
			(stroke
				(width 0.05)
				(type default)
			)
			(fill none)
			(layer "F.CrtYd")
		)
		(fp_rect
			(start -0.5 -0.25)
			(end 0.5 0.25)
			(stroke
				(width 0.15)
				(type solid)
			)
			(fill none)
			(layer "F.Fab")
		)
		(fp_text user "${REFERENCE}"
			(at -0.95 3.168 0)
			(layer "F.Fab")
			(hide yes)
			(effects
				(font
					(size 0.7 0.7)
					(thickness 0.15)
				)
				(justify left bottom)
			)
		)
		(fp_text user "License: Apache-2.0"
			(at -0.95 5.169 0)
			(layer "F.Fab")
			(hide yes)
			(effects
				(font
					(size 0.7 0.7)
					(thickness 0.15)
				)
				(justify left bottom)
			)
		)
		(fp_text user "Author: Antmicro"
			(at -0.95 4.169 0)
			(layer "F.Fab")
			(hide yes)
			(effects
				(font
					(size 0.7 0.7)
					(thickness 0.15)
				)
				(justify left bottom)
			)
		)
		(pad "1" smd roundrect
			(at -0.48 0)
			(size 0.59 0.64)
			(layers "F.Cu" "F.Paste" "F.Mask")
			(roundrect_rratio 0.25)
			(net 549 "/USB Debug, DP/USBC3_5V_PEN")
			(pintype "passive")
		)
		(pad "2" smd roundrect
			(at 0.48 0)
			(size 0.59 0.64)
			(layers "F.Cu" "F.Paste" "F.Mask")
			(roundrect_rratio 0.25)
			(net 657 "Net-(U9-EN)")
			(pintype "passive")
		)
	)
	(footprint "antmicro-footprints:R_0402_1005Metric"
		(layer "F.Cu")
		(at 44.141 104.394 -90)
		(descr "Resistor SMD 0402")
		(tags "resistor SMD 0402")
		(property "Reference" "R185"
			(at 1.356 -1.309 -90)
			(layer "F.SilkS")
			(effects
				(font
					(size 0.7 0.7)
					(thickness 0.15)
				)
				(justify left bottom)
			)
		)
		(property "Value" "R_100k_0402"
			(at 0 1.4 -90)
			(layer "F.Fab")
			(effects
				(font
					(size 0.7 0.7)
					(thickness 0.15)
				)
				(justify left bottom)
			)
		)
		(property "Footprint" "antmicro-footprints:R_0402_1005Metric"
			(at 0 0 -90)
			(layer "F.Fab")
			(hide yes)
			(effects
				(font
					(size 1.27 1.27)
					(thickness 0.15)
				)
			)
		)
		(property "Datasheet" "https://www.bourns.com/docs/product-datasheets/cr.pdf"
			(at 0 0 -90)
			(layer "F.Fab")
			(hide yes)
			(effects
				(font
					(size 1.27 1.27)
					(thickness 0.15)
				)
			)
		)
		(property "Author" "Antmicro"
			(at -60.253 148.535 0)
			(layer "F.Fab")
			(hide yes)
			(effects
				(font
					(size 1 1)
					(thickness 0.15)
				)
			)
		)
		(property "License" "Apache-2.0"
			(at -60.253 148.535 0)
			(layer "F.Fab")
			(hide yes)
			(effects
				(font
					(size 1 1)
					(thickness 0.15)
				)
			)
		)
		(property "MPN" "CR0402-FX-1003GLF"
			(at -60.253 148.535 0)
			(layer "F.Fab")
			(hide yes)
			(effects
				(font
					(size 1 1)
					(thickness 0.15)
				)
			)
		)
		(property "Manufacturer" "Bourns"
			(at -60.253 148.535 0)
			(layer "F.Fab")
			(hide yes)
			(effects
				(font
					(size 1 1)
					(thickness 0.15)
				)
			)
		)
		(property "Tolerance" "1%"
			(at -60.253 148.535 0)
			(layer "F.Fab")
			(hide yes)
			(effects
				(font
					(size 1 1)
					(thickness 0.15)
				)
			)
		)
		(property "Val" "100k"
			(at -60.253 148.535 0)
			(layer "F.Fab")
			(hide yes)
			(effects
				(font
					(size 1 1)
					(thickness 0.15)
				)
			)
		)
		(sheetname "Ethernet")
		(sheetfile "ethernet.kicad_sch")
		(attr smd)
		(fp_rect
			(start -0.925 -0.47)
			(end 0.925 0.47)
			(stroke
				(width 0.05)
				(type default)
			)
			(fill none)
			(layer "F.CrtYd")
		)
		(fp_rect
			(start -0.5 -0.25)
			(end 0.5 0.25)
			(stroke
				(width 0.15)
				(type solid)
			)
			(fill none)
			(layer "F.Fab")
		)
		(fp_text user "Author: Antmicro"
			(at -0.95 4.169 -90)
			(layer "F.Fab")
			(hide yes)
			(effects
				(font
					(size 0.7 0.7)
					(thickness 0.15)
				)
				(justify left bottom)
			)
		)
		(fp_text user "${REFERENCE}"
			(at -0.95 3.168 -90)
			(layer "F.Fab")
			(hide yes)
			(effects
				(font
					(size 0.7 0.7)
					(thickness 0.15)
				)
				(justify left bottom)
			)
		)
		(fp_text user "License: Apache-2.0"
			(at -0.95 5.169 -90)
			(layer "F.Fab")
			(hide yes)
			(effects
				(font
					(size 0.7 0.7)
					(thickness 0.15)
				)
				(justify left bottom)
			)
		)
		(pad "1" smd roundrect
			(at -0.48 0 270)
			(size 0.59 0.64)
			(layers "F.Cu" "F.Paste" "F.Mask")
			(roundrect_rratio 0.25)
			(net 106 "GNDD")
			(pintype "passive")
		)
		(pad "2" smd roundrect
			(at 0.48 0 270)
			(size 0.59 0.64)
			(layers "F.Cu" "F.Paste" "F.Mask")
			(roundrect_rratio 0.25)
			(net 127 "/Ethernet/POE_ACTIVE")
			(pintype "passive")
		)
	)
)
